G04*
G04 #@! TF.GenerationSoftware,Altium Limited,Altium Designer,23.0.1 (38)*
G04*
G04 Layer_Color=32768*
%FSLAX25Y25*%
%MOIN*%
G70*
G04*
G04 #@! TF.SameCoordinates,C48E81DB-6E20-4E2D-80E6-7C5AFAA1A21F*
G04*
G04*
G04 #@! TF.FilePolarity,Positive*
G04*
G01*
G75*
G36*
X345984Y-322753D02*
X326298D01*
Y-303067D01*
X345984D01*
Y-322753D01*
D02*
G37*
G36*
X346185Y-165408D02*
X326499D01*
Y-145722D01*
X346185D01*
Y-165408D01*
D02*
G37*
G36*
X542756Y-322764D02*
X523070D01*
Y-303079D01*
X542756D01*
Y-322764D01*
D02*
G37*
G36*
X542699Y-165591D02*
X523013D01*
Y-145905D01*
X542699D01*
Y-165591D01*
D02*
G37*
M02*
